G04 ================== begin FILE IDENTIFICATION RECORD ==================*
G04 Layout Name:  12433-2a.brd*
G04 Film Name:    P_OUTLINE*
G04 File Format:  Gerber RS274X*
G04 File Origin:  Cadence Allegro 16.5-S056*
G04 Origin Date:  Fri Dec 11 16:47:30 2015*
G04 *
G04 Layer:  BOARD GEOMETRY/PANEL_OUTLINE*
G04 *
G04 Offset:    (0.00 0.00)*
G04 Mirror:    No*
G04 Mode:      Positive*
G04 Rotation:  0*
G04 FullContactRelief:  No*
G04 UndefLineWidth:     6.00*
G04 ================== end FILE IDENTIFICATION RECORD ====================*
%FSLAX35Y35*MOIN*%
%IR0*IPPOS*OFA0.00000B0.00000*MIA0B0*SFA1.00000B1.00000*%
%ADD10C,.006*%
G75*
%LPD*%
G75*
G54D10*
G01X-222441Y169326D02*
Y39370D01*
G01D02*
G03X-214567Y31496I7874J0D01*
G01X-242126Y15000D02*
G03X-227126Y0I15000J0D01*
G01X-242126Y1953504D02*
Y15000D01*
G01X-215453Y19685D02*
G03I-6988J0D01*
G01X-84646Y0D02*
X-227126D01*
G01X-215453Y19685D02*
G03I-6988J0D01*
G01D02*
G03I-6988J0D01*
G01X-214567Y169326D02*
G03X-222441I-3937J0D01*
G01X-214567D02*
G03X-222441I-3937J0D01*
G01Y436255D02*
Y200034D01*
G01D02*
G03X-214567I3937J0D01*
G01X-222441D02*
G03X-214567I3937J0D01*
G01Y436255D02*
G03X-222441I-3937J0D01*
G01X-214567D02*
G03X-222441I-3937J0D01*
G01Y703184D02*
Y466963D01*
G01D02*
G03X-214567I3937J0D01*
G01X-222441D02*
G03X-214567I3937J0D01*
G01Y703184D02*
G03X-222441I-3937J0D01*
G01X-214567D02*
G03X-222441I-3937J0D01*
G01Y970901D02*
Y733892D01*
G01D02*
G03X-214567I3937J0D01*
G01X-222441D02*
G03X-214567I3937J0D01*
G01X-222441Y1234681D02*
Y997672D01*
G01X-214567Y970901D02*
G03X-222441I-3937J0D01*
G01Y997672D02*
G03X-214567I3937J0D01*
G01Y970901D02*
G03X-222441I-3937J0D01*
G01Y997672D02*
G03X-214567I3937J0D01*
G01X-222441Y1501610D02*
Y1265389D01*
G01D02*
G03X-214567I3937J0D01*
G01Y1234681D02*
G03X-222441I-3937J0D01*
G01Y1265389D02*
G03X-214567I3937J0D01*
G01Y1234681D02*
G03X-222441I-3937J0D01*
G01X-214567Y1501610D02*
G03X-222441I-3937J0D01*
G01X-214567D02*
G03X-222441I-3937J0D01*
G01Y1768539D02*
Y1532318D01*
G01D02*
G03X-214567I3937J0D01*
G01X-222441D02*
G03X-214567I3937J0D01*
G01Y1768539D02*
G03X-222441I-3937J0D01*
G01X-214567D02*
G03X-222441I-3937J0D01*
G01Y1799247D02*
G03X-214567I3937J0D01*
G01X-222441D02*
G03X-214567I3937J0D01*
G01X-222441Y1929134D02*
Y1799247D01*
G01X-214567Y1937008D02*
G03X-222441Y1929134I0J-7874D01*
G01X-227126Y1968504D02*
G03X-242126Y1953504I0J-15000D01*
G01X-215453Y1948819D02*
G03I-6988J0D01*
G01X-84638Y1968504D02*
X-227126D01*
G01X-215453Y1948819D02*
G03I-6988J0D01*
G01D02*
G03I-6988J0D01*
G01X-214567Y43307D02*
G03X-210630Y39370I3937J0D01*
G01X-214567Y43307D02*
G03X-210630Y39370I3937J0D01*
G01X-80709D02*
X-210630D01*
G01X-80709D02*
X-210630D01*
G01X-206693Y31496D02*
X-214567D01*
G01X-175984D02*
X-84646D01*
G01X-206693D02*
G03Y39370I0J3937D01*
G01X-175984D02*
G03Y31496I0J-3937D01*
G01X-206693D02*
X-214567D01*
G01X-84646Y0D02*
X-199567D01*
G01X-175984Y31496D02*
X-84646D01*
G01X-206693D02*
G03Y39370I0J3937D01*
G01X-175984D02*
G03Y31496I0J-3937D01*
G01X-214567Y43307D02*
Y1925197D01*
G01Y43307D02*
Y1925197D01*
G01Y149606D02*
Y43307D01*
G01Y149606D02*
Y43272D01*
G01Y1807087D02*
Y161417D01*
G01Y1807087D02*
Y161417D01*
G01Y1818898D02*
Y1925231D01*
G01Y1818898D02*
Y1925231D01*
G01X-210630Y1929134D02*
G03X-214567Y1925197I0J-3937D01*
G01X-210630Y1929134D02*
G03X-214567Y1925197I0J-3937D01*
G01X-210630Y1929134D02*
X-80709D01*
G01X-210630D02*
X-80709D01*
G01X-175984Y1937008D02*
G03Y1929134I0J-3937D01*
G01X-206693D02*
G03Y1937008I0J3937D01*
G01X-175984D02*
G03Y1929134I0J-3937D01*
G01X-206693D02*
G03Y1937008I0J3937D01*
G01X-175984D02*
X-84638D01*
G01X-214567D02*
X-206693D01*
G01X-84638Y1968504D02*
X-199567D01*
G01X-175984Y1937008D02*
X-84638D01*
G01X-214567D02*
X-206693D01*
G01X-76772Y3937D02*
G03X-72835Y0I3937J0D01*
G01X-76772Y35433D02*
G03X-80709Y39370I-3937J0D01*
G01X-76772Y35433D02*
G03X-80709Y39370I-3937J0D01*
G01X-76772Y3937D02*
G03X-72835Y0I3937J0D01*
G01X-11811D02*
X-72835D01*
G01X-11811D02*
X-72835D01*
G01X-76772Y3937D02*
Y35433D01*
G01Y3937D02*
Y35433D01*
G01X-72835Y0D02*
X-11811D01*
G01X-76772Y3937D02*
G03X-72835Y0I3937J0D01*
G01X-84646Y7874D02*
Y0D01*
G01X-76772Y7874D02*
G03X-84646I-3937J0D01*
G01Y31496D02*
G03X-76772I3937J0D01*
G01X-72835Y0D02*
X-11811D01*
G01X-76772Y3937D02*
G03X-72835Y0I3937J0D01*
G01X-84646Y7874D02*
Y0D01*
G01X-76772Y7874D02*
G03X-84646I-3937J0D01*
G01Y31496D02*
G03X-76772I3937J0D01*
G01X-80709Y1929134D02*
G03X-76772Y1933071I0J3937D01*
G01X-80709Y1929134D02*
G03X-76772Y1933071I0J3937D01*
G01D02*
Y1964567D01*
G01Y1933071D02*
Y1964567D01*
G01X-76763Y1937008D02*
G03X-84638I-3937J0D01*
G01X-72835Y1968504D02*
G03X-76772Y1964567I0J-3937D01*
G01X-72835Y1968504D02*
G03X-76772Y1964567I0J-3937D01*
G01X-72835Y1968504D02*
X-11811D01*
G01X-72835D02*
X-11811D01*
G01X-72835D02*
G03X-76772Y1964567I0J-3937D01*
G01X-11811Y1968504D02*
X-72835D01*
G01X-84638Y1960889D02*
Y1968504D01*
G01Y1960889D02*
G03X-76763I3938J0D01*
G01X-72835Y1968504D02*
G03X-76772Y1964567I0J-3937D01*
G01X-11811Y1968504D02*
X-72835D01*
G01X-84638Y1960889D02*
Y1968504D01*
G01Y1960889D02*
G03X-76763I3938J0D01*
G01X-11811Y0D02*
G03X-7874Y3937I0J3937D01*
G01X-11811Y0D02*
G03X-7874Y3937I0J3937D01*
G01Y43110D02*
Y3937D01*
G01Y43110D02*
Y3937D01*
G01X0D02*
G03X3937Y0I3937J0D01*
G01X0Y3937D02*
G03X3937Y0I3937J0D01*
G01X0Y3937D02*
Y43110D01*
G01Y3937D02*
Y43110D01*
G01X64961Y0D02*
X3937D01*
G01X64961D02*
X3937D01*
G01X0Y3937D02*
G03X3937Y0I3937J0D01*
G01X0Y1964567D02*
Y3937D01*
G01X3937Y0D02*
X64961D01*
G01X-7874Y3937D02*
Y1964567D01*
G01X-11811Y0D02*
G03X-7874Y3937I0J3937D01*
G01X0Y11811D02*
G03X-7874I-3937J0D01*
G01Y42520D02*
G03X0I3937J0D01*
G01Y3937D02*
G03X3937Y0I3937J0D01*
G01X0Y1964567D02*
Y3937D01*
G01X3937Y0D02*
X64961D01*
G01X-7874Y3937D02*
Y1964567D01*
G01X-11811Y0D02*
G03X-7874Y3937I0J3937D01*
G01X0Y11811D02*
G03X-7874I-3937J0D01*
G01Y42520D02*
G03X0I3937J0D01*
G01X-7874Y93110D02*
Y43110D01*
G01Y93110D02*
Y43110D01*
G01X0D02*
Y93110D01*
G01Y43110D02*
Y93110D01*
G01X-7874Y214764D02*
Y93110D01*
G01Y214764D02*
Y93110D01*
G01X0D02*
Y214764D01*
G01Y93110D02*
Y214764D01*
G01X-7874Y226968D02*
Y214764D01*
G01Y226968D02*
Y214764D01*
G01Y342461D02*
Y226968D01*
G01Y342461D02*
Y226968D01*
G01X0Y226969D02*
Y342461D01*
G01Y226969D02*
Y342461D01*
G01Y214764D02*
Y226969D01*
G01Y214764D02*
Y226969D01*
G01Y278740D02*
G03X-7874I-3937J0D01*
G01X0D02*
G03X-7874I-3937J0D01*
G01Y354665D02*
Y342461D01*
G01Y354665D02*
Y342461D01*
G01X0D02*
Y354665D01*
G01Y342461D02*
Y354665D01*
G01X-7874Y309449D02*
G03X0I3937J0D01*
G01X-7874D02*
G03X0I3937J0D01*
G01X-7874Y476339D02*
Y354665D01*
G01Y476339D02*
Y354665D01*
G01X0D02*
Y476339D01*
G01Y354665D02*
Y476339D01*
G01X-7874Y526339D02*
Y476339D01*
G01Y526339D02*
Y476339D01*
G01X0D02*
Y526339D01*
G01Y476339D02*
Y526339D01*
G01X-7874Y736181D02*
Y526339D01*
G01Y736181D02*
Y526339D01*
G01X0D02*
Y736181D01*
G01Y526339D02*
Y736181D01*
G01Y545669D02*
G03X-7874I-3937J0D01*
G01X0D02*
G03X-7874I-3937J0D01*
G01Y576378D02*
G03X0I3937J0D01*
G01X-7874D02*
G03X0I3937J0D01*
G01X-7874Y786181D02*
Y736181D01*
G01Y786181D02*
Y736181D01*
G01X0D02*
Y786181D01*
G01Y736181D02*
Y786181D01*
G01X-7874Y907815D02*
Y786181D01*
G01Y907815D02*
Y786181D01*
G01X0D02*
Y907815D01*
G01Y786181D02*
Y907815D01*
G01X-7874Y862205D02*
G03X0I3937J0D01*
G01Y831496D02*
G03X-7874I-3937J0D01*
G01Y862205D02*
G03X0I3937J0D01*
G01Y831496D02*
G03X-7874I-3937J0D01*
G01Y920020D02*
Y907815D01*
G01Y920020D02*
Y907815D01*
G01X0D02*
Y920020D01*
G01Y907815D02*
Y920020D01*
G01X-7874Y1048484D02*
Y920020D01*
G01Y1048484D02*
Y920020D01*
G01X0D02*
Y1048484D01*
G01Y920020D02*
Y1048484D01*
G01X-7874Y1060689D02*
Y1048484D01*
G01Y1060689D02*
Y1048484D01*
G01Y1182323D02*
Y1060689D01*
G01Y1182323D02*
Y1060689D01*
G01X0D02*
Y1182323D01*
G01Y1060689D02*
Y1182323D01*
G01Y1048484D02*
Y1060689D01*
G01Y1048484D02*
Y1060689D01*
G01Y1106299D02*
G03X-7874I-3937J0D01*
G01X0D02*
G03X-7874I-3937J0D01*
G01Y1137008D02*
G03X0I3937J0D01*
G01X-7874D02*
G03X0I3937J0D01*
G01X-7874Y1232323D02*
Y1182323D01*
G01Y1232323D02*
Y1182323D01*
G01X0D02*
Y1232323D01*
G01Y1182323D02*
Y1232323D01*
G01X-7874Y1442165D02*
Y1232323D01*
G01Y1442165D02*
Y1232323D01*
G01X0D02*
Y1442165D01*
G01Y1232323D02*
Y1442165D01*
G01X-7874Y1422835D02*
G03X0I3937J0D01*
G01Y1392126D02*
G03X-7874I-3937J0D01*
G01Y1422835D02*
G03X0I3937J0D01*
G01Y1392126D02*
G03X-7874I-3937J0D01*
G01Y1492165D02*
Y1442165D01*
G01Y1492165D02*
Y1442165D01*
G01X0D02*
Y1492165D01*
G01Y1442165D02*
Y1492165D01*
G01X-7874Y1613839D02*
Y1492165D01*
G01Y1613839D02*
Y1492165D01*
G01X0D02*
Y1613839D01*
G01Y1492165D02*
Y1613839D01*
G01X-7874Y1626043D02*
Y1613839D01*
G01Y1626043D02*
Y1613839D01*
G01Y1741535D02*
Y1626043D01*
G01Y1741535D02*
Y1626043D01*
G01X0D02*
Y1741535D01*
G01Y1626043D02*
Y1741535D01*
G01Y1613839D02*
Y1626043D01*
G01Y1613839D02*
Y1626043D01*
G01Y1659055D02*
G03X-7874I-3937J0D01*
G01X0D02*
G03X-7874I-3937J0D01*
G01Y1689764D02*
G03X0I3937J0D01*
G01X-7874D02*
G03X0I3937J0D01*
G01X-7874Y1753740D02*
Y1741535D01*
G01Y1753740D02*
Y1741535D01*
G01Y1875394D02*
Y1753740D01*
G01Y1875394D02*
Y1753740D01*
G01X0D02*
Y1875394D01*
G01Y1753740D02*
Y1875394D01*
G01Y1741535D02*
Y1753740D01*
G01Y1741535D02*
Y1753740D01*
G01X-7874Y1925394D02*
Y1875394D01*
G01Y1925394D02*
Y1875394D01*
G01X0D02*
Y1925394D01*
G01Y1875394D02*
Y1925394D01*
G01X-7874Y1964567D02*
Y1925394D01*
G01Y1964567D02*
Y1925394D01*
G01X0D02*
Y1964567D01*
G01Y1925394D02*
Y1964567D01*
G01Y1925984D02*
G03X-7874I-3937J0D01*
G01X0D02*
G03X-7874I-3937J0D01*
G01Y1964567D02*
G03X-11811Y1968504I-3937J0D01*
G01X-7874Y1964567D02*
G03X-11811Y1968504I-3937J0D01*
G01X3937D02*
G03X0Y1964567I0J-3937D01*
G01X3937Y1968504D02*
G03X0Y1964567I0J-3937D01*
G01X3937Y1968504D02*
X64961D01*
G01X3937D02*
X64961D01*
G01X3937D02*
G03X0Y1964567I0J-3937D01*
G01X64961Y1968504D02*
X3937D01*
G01X-7874Y1964567D02*
G03X-11811Y1968504I-3937J0D01*
G01X-7874Y1956693D02*
G03X0I3937J0D01*
G01X3937Y1968504D02*
G03X0Y1964567I0J-3937D01*
G01X64961Y1968504D02*
X3937D01*
G01X-7874Y1964567D02*
G03X-11811Y1968504I-3937J0D01*
G01X-7874Y1956693D02*
G03X0I3937J0D01*
G01X168110Y31496D02*
X76763D01*
G01X72835Y39370D02*
G03X68898Y35433I0J-3937D01*
G01X72835Y39370D02*
G03X68898Y35433I0J-3937D01*
G01X64961Y0D02*
G03X68898Y3937I0J3937D01*
G01X64961Y0D02*
G03X68898Y3937I0J3937D01*
G01Y35433D02*
Y3937D01*
G01Y35433D02*
Y3937D01*
G01X202756Y39370D02*
X72835D01*
G01X202756D02*
X72835D01*
G01D02*
X202756D01*
G01X72835D02*
G03X68898Y35433I0J-3937D01*
G01Y3937D02*
Y35485D01*
G01X64961Y0D02*
G03X68898Y3937I0J3937D01*
G01X76763D02*
G03X80700Y0I3937J0D01*
G01X76763Y7615D02*
Y3937D01*
G01X80700Y0D02*
X340551D01*
G01X168110Y31496D02*
X76763D01*
G01Y7615D02*
G03X68889I-3937J0D01*
G01Y31496D02*
G03X76763I3937J0D01*
G01X72835Y39370D02*
X202756D01*
G01X72835D02*
G03X68898Y35433I0J-3937D01*
G01Y3937D02*
Y35485D01*
G01X64961Y0D02*
G03X68898Y3937I0J3937D01*
G01X76763D02*
G03X80700Y0I3937J0D01*
G01X76763Y7615D02*
Y3937D01*
G01X80700Y0D02*
X340551D01*
G01X168110Y31496D02*
X76763D01*
G01Y7615D02*
G03X68889I-3937J0D01*
G01Y31496D02*
G03X76763I3937J0D01*
G01X68898Y1933071D02*
G03X72835Y1929134I3937J0D01*
G01X68898Y1933071D02*
G03X72835Y1929134I3937J0D01*
G01D02*
X202756D01*
G01X72835D02*
X202756D01*
G01X68898Y1964567D02*
Y1933071D01*
G01Y1964567D02*
Y1933071D01*
G01D02*
Y1964567D01*
G01Y1933071D02*
G03X72835Y1929134I3937J0D01*
G01X202756D02*
X72835D01*
G01X68898Y1933071D02*
Y1964567D01*
G01Y1933071D02*
G03X72835Y1929134I3937J0D01*
G01X202756D02*
X72835D01*
G01X68898Y1964567D02*
G03X64961Y1968504I-3937J0D01*
G01X68898Y1964567D02*
G03X64961Y1968504I-3937J0D01*
G01X68898Y1964567D02*
G03X64961Y1968504I-3937J0D01*
G01X109377D02*
X80709D01*
G01D02*
G03X76772Y1964567I0J-3937D01*
G01Y1960630D02*
Y1964567D01*
G01X168110Y1937008D02*
X76772D01*
G01X68898Y1960630D02*
G03X76772I3937J0D01*
G01Y1937008D02*
G03X68898I-3937J0D01*
G01Y1964567D02*
G03X64961Y1968504I-3937J0D01*
G01X109377D02*
X80709D01*
G01D02*
G03X76772Y1964567I0J-3937D01*
G01Y1960630D02*
Y1964567D01*
G01X168110Y1937008D02*
X76772D01*
G01X68898Y1960630D02*
G03X76772I3937J0D01*
G01Y1937008D02*
G03X68898I-3937J0D01*
G01X118011Y1968504D02*
X142520D01*
G01X109377D02*
X110137D01*
G01D02*
G03X118011I3937J0D01*
G01X110137D02*
G03X118011I3937J0D01*
G01X168110Y31496D02*
G03Y39370I0J3937D01*
G01Y31496D02*
G03Y39370I0J3937D01*
G01Y1929134D02*
G03Y1937008I0J3937D01*
G01Y1929134D02*
G03Y1937008I0J3937D01*
G01X340559Y1968504D02*
X142520D01*
G01X340559D02*
X142520D01*
G01X202756Y39370D02*
G03X206693Y43307I0J3937D01*
G01X202756Y39370D02*
G03X206693Y43307I0J3937D01*
G01X202756Y39370D02*
G03X206693Y43307I0J3937D01*
G01X218504Y39370D02*
X348425D01*
G01X214567Y43307D02*
G03X218504Y39370I3937J0D01*
G01X222441Y31496D02*
X198819D01*
G01X222441D02*
G03Y39370I0J3937D01*
G01X198819D02*
G03Y31496I0J-3937D01*
G01X202756Y39370D02*
G03X206693Y43307I0J3937D01*
G01X218504Y39370D02*
X348425D01*
G01X214567Y43307D02*
G03X218504Y39370I3937J0D01*
G01X222441Y31496D02*
X198819D01*
G01X222441D02*
G03Y39370I0J3937D01*
G01X198819D02*
G03Y31496I0J-3937D01*
G01X214567Y161417D02*
Y43307D01*
G01X206693Y1925197D02*
Y43307D01*
G01Y1925197D02*
Y43307D01*
G01Y161417D02*
Y1807087D01*
G01X214567D02*
Y161417D01*
G01Y169291D02*
G03X206693I-3937J0D01*
G01Y161417D02*
Y1807087D01*
G01X214567D02*
Y161417D01*
G01Y169291D02*
G03X206693I-3937J0D01*
G01Y200000D02*
G03X214567I3937J0D01*
G01X206693D02*
G03X214567I3937J0D01*
G01Y436220D02*
G03X206693I-3937J0D01*
G01X214567D02*
G03X206693I-3937J0D01*
G01Y466929D02*
G03X214567I3937J0D01*
G01X206693D02*
G03X214567I3937J0D01*
G01Y703149D02*
G03X206693I-3937J0D01*
G01X214567D02*
G03X206693I-3937J0D01*
G01Y733858D02*
G03X214567I3937J0D01*
G01X206693D02*
G03X214567I3937J0D01*
G01Y970867D02*
G03X206693I-3937J0D01*
G01Y997637D02*
G03X214567I3937J0D01*
G01Y970867D02*
G03X206693I-3937J0D01*
G01Y997637D02*
G03X214567I3937J0D01*
G01X206693Y1265355D02*
G03X214567I3937J0D01*
G01Y1234646D02*
G03X206693I-3937J0D01*
G01Y1265355D02*
G03X214567I3937J0D01*
G01Y1234646D02*
G03X206693I-3937J0D01*
G01X214567Y1501575D02*
G03X206693I-3937J0D01*
G01X214567D02*
G03X206693I-3937J0D01*
G01Y1532284D02*
G03X214567I3937J0D01*
G01X206693D02*
G03X214567I3937J0D01*
G01Y1768504D02*
G03X206693I-3937J0D01*
G01X214567D02*
G03X206693I-3937J0D01*
G01X214567Y1807087D02*
Y1925197D01*
G01X206693Y1799213D02*
G03X214567I3937J0D01*
G01X206693D02*
G03X214567I3937J0D01*
G01X206693Y1925197D02*
G03X202756Y1929134I-3937J0D01*
G01X206693Y1925197D02*
G03X202756Y1929134I-3937J0D01*
G01X206693Y1925197D02*
G03X202756Y1929134I-3937J0D01*
G01X218504D02*
G03X214567Y1925197I0J-3937D01*
G01X348425Y1929134D02*
X218504D01*
G01X198819Y1937008D02*
G03Y1929134I0J-3937D01*
G01X222441D02*
G03Y1937008I0J3937D01*
G01X206693Y1925197D02*
G03X202756Y1929134I-3937J0D01*
G01X218504D02*
G03X214567Y1925197I0J-3937D01*
G01X348425Y1929134D02*
X218504D01*
G01X198819Y1937008D02*
G03Y1929134I0J-3937D01*
G01X222441D02*
G03Y1937008I0J3937D01*
G01X198819D02*
X222441D01*
G01X198819D02*
X222441D01*
G01X253150Y31496D02*
X344488D01*
G01X253150Y39370D02*
G03Y31496I0J-3937D01*
G01D02*
X344488D01*
G01X253150Y39370D02*
G03Y31496I0J-3937D01*
G01Y1937008D02*
G03Y1929134I0J-3937D01*
G01Y1937008D02*
G03Y1929134I0J-3937D01*
G01Y1937008D02*
X344496D01*
G01X253150D02*
X344496D01*
G01X340551Y0D02*
G03X344488Y3937I0J3937D01*
G01X340551Y0D02*
G03X344488Y3937I0J3937D01*
G01X344496Y1964567D02*
G03X340559Y1968504I-3937J0D01*
G01X344496Y1964567D02*
G03X340559Y1968504I-3937J0D01*
G01X356299Y0D02*
X417323D01*
G01X352362Y3937D02*
G03X356299Y0I3937J0D01*
G01X352362Y35433D02*
Y3937D01*
G01Y35433D02*
G03X348425Y39370I-3937J0D01*
G01X344488Y7874D02*
Y3937D01*
G01X352362Y7874D02*
G03X344488I-3937J0D01*
G01Y31496D02*
G03X352362I3937J0D01*
G01X356299Y0D02*
X417323D01*
G01X352362Y3937D02*
G03X356299Y0I3937J0D01*
G01X352362Y35433D02*
Y3937D01*
G01Y35433D02*
G03X348425Y39370I-3937J0D01*
G01X344488Y7874D02*
Y3937D01*
G01X352362Y7874D02*
G03X344488I-3937J0D01*
G01Y31496D02*
G03X352362I3937J0D01*
G01X348425Y1929134D02*
G03X352362Y1933071I0J3937D01*
G01Y1964567D02*
Y1933071D01*
G01X348425Y1929134D02*
G03X352362Y1933071I0J3937D01*
G01Y1964567D02*
Y1933071D01*
G01X356299Y1968504D02*
G03X352362Y1964567I0J-3937D01*
G01X417323Y1968504D02*
X356299D01*
G01X344496Y1960889D02*
Y1964567D01*
G01Y1960889D02*
G03X352370I3937J0D01*
G01Y1937008D02*
G03X344496I-3937J0D01*
G01X356299Y1968504D02*
G03X352362Y1964567I0J-3937D01*
G01X417323Y1968504D02*
X356299D01*
G01X344496Y1960889D02*
Y1964567D01*
G01Y1960889D02*
G03X352370I3937J0D01*
G01Y1937008D02*
G03X344496I-3937J0D01*
G01X429134Y3937D02*
G03X433071Y0I3937J0D01*
G01X429134Y1964567D02*
Y3937D01*
G01X433071Y0D02*
X494095D01*
G01X421260Y3937D02*
Y1964567D01*
G01X417323Y0D02*
G03X421260Y3937I0J3937D01*
G01X429134Y11811D02*
G03X421260I-3937J0D01*
G01Y42520D02*
G03X429134I3937J0D01*
G01Y3937D02*
G03X433071Y0I3937J0D01*
G01X429134Y1964567D02*
Y3937D01*
G01X433071Y0D02*
X494095D01*
G01X421260Y3937D02*
Y1964567D01*
G01X417323Y0D02*
G03X421260Y3937I0J3937D01*
G01X429134Y11811D02*
G03X421260I-3937J0D01*
G01Y42520D02*
G03X429134I3937J0D01*
G01Y278740D02*
G03X421260I-3937J0D01*
G01X429134D02*
G03X421260I-3937J0D01*
G01Y309449D02*
G03X429134I3937J0D01*
G01X421260D02*
G03X429134I3937J0D01*
G01Y545669D02*
G03X421260I-3937J0D01*
G01X429134D02*
G03X421260I-3937J0D01*
G01Y576378D02*
G03X429134I3937J0D01*
G01X421260D02*
G03X429134I3937J0D01*
G01X421260Y862205D02*
G03X429134I3937J0D01*
G01Y831496D02*
G03X421260I-3937J0D01*
G01Y862205D02*
G03X429134I3937J0D01*
G01Y831496D02*
G03X421260I-3937J0D01*
G01X429134Y1106299D02*
G03X421260I-3937J0D01*
G01X429134D02*
G03X421260I-3937J0D01*
G01Y1137008D02*
G03X429134I3937J0D01*
G01X421260D02*
G03X429134I3937J0D01*
G01X421260Y1422835D02*
G03X429134I3937J0D01*
G01Y1392126D02*
G03X421260I-3937J0D01*
G01Y1422835D02*
G03X429134I3937J0D01*
G01Y1392126D02*
G03X421260I-3937J0D01*
G01X429134Y1659055D02*
G03X421260I-3937J0D01*
G01X429134D02*
G03X421260I-3937J0D01*
G01Y1689764D02*
G03X429134I3937J0D01*
G01X421260D02*
G03X429134I3937J0D01*
G01Y1925984D02*
G03X421260I-3937J0D01*
G01X429134D02*
G03X421260I-3937J0D01*
G01X433071Y1968504D02*
G03X429134Y1964567I0J-3937D01*
G01X494095Y1968504D02*
X433071D01*
G01X421260Y1964567D02*
G03X417323Y1968504I-3937J0D01*
G01X421260Y1956693D02*
G03X429134I3937J0D01*
G01X433071Y1968504D02*
G03X429134Y1964567I0J-3937D01*
G01X494095Y1968504D02*
X433071D01*
G01X421260Y1964567D02*
G03X417323Y1968504I-3937J0D01*
G01X421260Y1956693D02*
G03X429134I3937J0D01*
G01X433071Y1968504D02*
G03X429134Y1964567I0J-3937D01*
G01X421260D02*
G03X417323Y1968504I-3937J0D01*
G01X494095Y0D02*
G03X498032Y3937I0J3937D01*
G01X494095Y0D02*
G03X498032Y3937I0J3937D01*
G01Y1964567D02*
G03X494095Y1968504I-3937J0D01*
G01X498032Y1964567D02*
G03X494095Y1968504I-3937J0D01*
G01X501969Y39370D02*
X631890D01*
G01X501969D02*
G03X498032Y35433I0J-3937D01*
G01Y3937D02*
Y35433D01*
G01X505897Y0D02*
X648386D01*
G01X505897Y7615D02*
Y0D01*
G01X597244Y31496D02*
X505897D01*
G01Y7615D02*
G03X498023I-3937J0D01*
G01Y31496D02*
G03X505897I3937J0D01*
G01X501969Y39370D02*
X631890D01*
G01X501969D02*
G03X498032Y35433I0J-3937D01*
G01Y3937D02*
Y35433D01*
G01X505897Y0D02*
X620827D01*
G01X505897Y7615D02*
Y0D01*
G01X597244Y31496D02*
X505897D01*
G01Y7615D02*
G03X498023I-3937J0D01*
G01Y31496D02*
G03X505897I3937J0D01*
G01X498032Y1933071D02*
Y1960630D01*
G01Y1933071D02*
G03X501969Y1929134I3937J0D01*
G01X631890D02*
X501969D01*
G01X498032Y1933071D02*
Y1964567D01*
G01Y1933071D02*
G03X501969Y1929134I3937J0D01*
G01X631890D02*
X501969D01*
G01X505906Y1960630D02*
Y1968504D01*
G01D02*
X648386D01*
G01X597244Y1937008D02*
X505906D01*
G01X498032Y1960630D02*
G03X505906I3937J0D01*
G01Y1937008D02*
G03X498032I-3937J0D01*
G01X505906Y1960630D02*
Y1968504D01*
G01D02*
X620827D01*
G01X597244Y1937008D02*
X505906D01*
G01X498032Y1960630D02*
G03X505906I3937J0D01*
G01Y1937008D02*
G03X498032I-3937J0D01*
G01X643701Y169256D02*
Y39370D01*
G01X635827Y31496D02*
G03X643701Y39370I0J7874D01*
G01X650689Y19685D02*
G03I-6988J0D01*
G01X631890Y39370D02*
G03X635827Y43307I0J3937D01*
G01Y31496D02*
X627953D01*
G01X597244D02*
G03Y39370I0J3937D01*
G01X627953D02*
G03Y31496I0J-3937D01*
G01X650689Y19685D02*
G03I-6988J0D01*
G01X631890Y39370D02*
G03X635827Y43307I0J3937D01*
G01Y31496D02*
X627953D01*
G01X597244D02*
G03Y39370I0J3937D01*
G01X627953D02*
G03Y31496I0J-3937D01*
G01X635827Y161417D02*
Y43307D01*
G01X643701Y169256D02*
G03X635827I-3937J0D01*
G01X643701D02*
G03X635827I-3937J0D01*
G01Y161417D02*
Y1807087D01*
G01Y161417D02*
Y1807087D01*
G01X643701Y436186D02*
Y199965D01*
G01X635827D02*
G03X643701I3937J0D01*
G01X635827D02*
G03X643701I3937J0D01*
G01Y436186D02*
G03X635827I-3937J0D01*
G01X643701D02*
G03X635827I-3937J0D01*
G01X643701Y703115D02*
Y466894D01*
G01X635827D02*
G03X643701I3937J0D01*
G01X635827D02*
G03X643701I3937J0D01*
G01Y703115D02*
G03X635827I-3937J0D01*
G01X643701D02*
G03X635827I-3937J0D01*
G01X643701Y970832D02*
Y733823D01*
G01X635827D02*
G03X643701I3937J0D01*
G01X635827D02*
G03X643701I3937J0D01*
G01Y1234611D02*
Y997603D01*
G01X635827D02*
G03X643701I3937J0D01*
G01Y970832D02*
G03X635827I-3937J0D01*
G01Y997603D02*
G03X643701I3937J0D01*
G01Y970832D02*
G03X635827I-3937J0D01*
G01X643701Y1501541D02*
Y1265320D01*
G01X635827D02*
G03X643701I3937J0D01*
G01Y1234611D02*
G03X635827I-3937J0D01*
G01Y1265320D02*
G03X643701I3937J0D01*
G01Y1234611D02*
G03X635827I-3937J0D01*
G01X643701Y1501541D02*
G03X635827I-3937J0D01*
G01X643701D02*
G03X635827I-3937J0D01*
G01X643701Y1768470D02*
Y1532249D01*
G01X635827D02*
G03X643701I3937J0D01*
G01X635827D02*
G03X643701I3937J0D01*
G01Y1768470D02*
G03X635827I-3937J0D01*
G01X643701D02*
G03X635827I-3937J0D01*
G01Y1799178D02*
G03X643701I3937J0D01*
G01X635827D02*
G03X643701I3937J0D01*
G01Y1929134D02*
Y1799178D01*
G01X635827Y1818898D02*
Y1807087D01*
G01Y1818898D02*
Y1925197D01*
G01Y1818898D02*
Y1925197D01*
G01X643701Y1929134D02*
G03X635827Y1937008I-7874J0D01*
G01Y1925197D02*
G03X631890Y1929134I-3937J0D01*
G01X627953Y1937008D02*
G03Y1929134I0J-3937D01*
G01X597244D02*
G03Y1937008I0J3937D01*
G01X635827Y1925197D02*
G03X631890Y1929134I-3937J0D01*
G01X627953Y1937008D02*
G03Y1929134I0J-3937D01*
G01X597244D02*
G03Y1937008I0J3937D01*
G01X650689Y1948819D02*
G03I-6988J0D01*
G01X627953Y1937008D02*
X635827D01*
G01X650689Y1948819D02*
G03I-6988J0D01*
G01X627953Y1937008D02*
X635827D01*
G01X650689Y1948819D02*
G03I-6988J0D01*
G01X648386Y0D02*
G03X663386Y15000I0J15000D01*
G01Y1953504D02*
Y15000D01*
G01Y1953504D02*
G03X648386Y1968504I-15000J0D01*
M02*
